(kicad_pcb
	(version 20260206)
	(generator "pcbnew")
	(generator_version "10.0")
	(general
		(thickness 1.6)
		(legacy_teardrops no)
	)
	(paper "A4")
	(title_block
		(title "04192023_DAF0TMB3IC0_F0TG_MB_C_brd_V02_OCP.brd")
		(comment 1 "Grand Teton / footprint 2783 of 8354 (U26), pads 3006-3115 of 6102")
	)
	(layers
		(0 "F.Cu" signal "TOP")
		(4 "In1.Cu" signal "GND")
		(6 "In2.Cu" signal "IN1")
		(8 "In3.Cu" signal "GND1")
		(10 "In4.Cu" signal "IN2")
		(12 "In5.Cu" signal "GND2")
		(14 "In6.Cu" signal "IN3")
		(16 "In7.Cu" signal "GND3")
		(18 "In8.Cu" signal "VCC")
		(20 "In9.Cu" signal "VCC1")
		(22 "In10.Cu" signal "GND4")
		(24 "In11.Cu" signal "IN4")
		(26 "In12.Cu" signal "GND5")
		(28 "In13.Cu" signal "IN5")
		(30 "In14.Cu" signal "GND6")
		(32 "In15.Cu" signal "IN6")
		(34 "In16.Cu" signal "GND7")
		(2 "B.Cu" signal "BOTTOM")
		(9 "F.Adhes" user "F.Adhesive")
		(11 "B.Adhes" user "B.Adhesive")
		(13 "F.Paste" user "Package Geometry/Pastemask Top")
		(15 "B.Paste" user "Package Geometry/Pastemask Bottom")
		(5 "F.SilkS" user "Ref Des/Silkscreen Top")
		(7 "B.SilkS" user "Ref Des/Silkscreen Bottom")
		(1 "F.Mask" user "Board Geometry/Soldermask Top")
		(3 "B.Mask" user "Board Geometry/Soldermask Bottom")
		(17 "Dwgs.User" user "User.Drawings")
		(19 "Cmts.User" user "User.Comments")
		(21 "Eco1.User" user "User.Eco1")
		(23 "Eco2.User" user "User.Eco2")
		(25 "Edge.Cuts" user "Board Geometry/Outline")
		(27 "Margin" user)
		(31 "F.CrtYd" user "Package Geometry/Place Bound Top")
		(29 "B.CrtYd" user "Package Geometry/Place Bound Bottom")
		(35 "F.Fab" user "Ref Des/Assembly Top")
		(33 "B.Fab" user "Ref Des/Assembly Bottom")
	)
	(footprint ""
		(layer "F.Cu")
		(at 111.927894 -258.880356 180)
		(property "Reference" "U26"
			(at -45.05579 -61.794136 0)
			(unlocked yes)
			(layer "F.SilkS")
			(effects
				(font
					(size 0.7874 0.5842)
					(thickness 0.1524)
				)
			)
		)
		(property "Value" ""
			(at 0 0 180)
			(layer "F.Fab")
			(effects
				(font
					(size 1.27 1.27)
				)
			)
		)
		(duplicate_pad_numbers_are_jumpers no)
		(pad "CC57" smd circle
			(at 17.239996 15.750032 180)
			(size 0.450088 0.450088)
			(layers "F.Cu" "F.Mask" "F.Paste")
			(net "M_C_CPU1_SB_DQ<2>")
		)
		(pad "CC58" smd circle
			(at 18.18005 15.750032 180)
			(size 0.450088 0.450088)
			(layers "F.Cu" "F.Mask" "F.Paste")
			(net "GND")
		)
		(pad "CC59" smd circle
			(at 19.120104 15.750032 180)
			(size 0.450088 0.450088)
			(layers "F.Cu" "F.Mask" "F.Paste")
			(net "M_D_CPU1_SB_DQ<1>")
		)
		(pad "CC60" smd circle
			(at 20.059904 15.750032 180)
			(size 0.450088 0.450088)
			(layers "F.Cu" "F.Mask" "F.Paste")
			(net "M_D_CPU1_SB_DQ<2>")
		)
		(pad "CC61" smd circle
			(at 20.999958 15.750032 180)
			(size 0.450088 0.450088)
			(layers "F.Cu" "F.Mask" "F.Paste")
			(net "GND")
		)
		(pad "CC62" smd circle
			(at 21.940012 15.750032 180)
			(size 0.450088 0.450088)
			(layers "F.Cu" "F.Mask" "F.Paste")
			(net "M_B_CPU1_SB_DQ<1>")
		)
		(pad "CC63" smd circle
			(at 22.880066 15.750032 180)
			(size 0.450088 0.450088)
			(layers "F.Cu" "F.Mask" "F.Paste")
			(net "GND")
		)
		(pad "CC64" smd circle
			(at 23.82012 15.750032 180)
			(size 0.450088 0.450088)
			(layers "F.Cu" "F.Mask" "F.Paste")
			(net "M_B_CPU1_SB_DQ<2>")
		)
		(pad "CC65" smd circle
			(at 24.75992 15.750032 180)
			(size 0.450088 0.450088)
			(layers "F.Cu" "F.Mask" "F.Paste")
			(net "GND")
		)
		(pad "CC66" smd circle
			(at 25.699974 15.750032 180)
			(size 0.450088 0.450088)
			(layers "F.Cu" "F.Mask" "F.Paste")
			(net "M_F_CPU1_SB_DQ<1>")
		)
		(pad "CC67" smd circle
			(at 26.640028 15.750032 180)
			(size 0.450088 0.450088)
			(layers "F.Cu" "F.Mask" "F.Paste")
			(net "M_F_CPU1_SB_DQ<2>")
		)
		(pad "CC68" smd circle
			(at 27.580082 15.750032 180)
			(size 0.450088 0.450088)
			(layers "F.Cu" "F.Mask" "F.Paste")
			(net "GND")
		)
		(pad "CC69" smd circle
			(at 28.519882 15.750032 180)
			(size 0.450088 0.450088)
			(layers "F.Cu" "F.Mask" "F.Paste")
			(net "M_E_CPU1_SB_DQ<1>")
		)
		(pad "CC70" smd circle
			(at 29.459936 15.750032 180)
			(size 0.450088 0.450088)
			(layers "F.Cu" "F.Mask" "F.Paste")
			(net "GND")
		)
		(pad "CC71" smd circle
			(at 30.39999 15.750032 180)
			(size 0.450088 0.450088)
			(layers "F.Cu" "F.Mask" "F.Paste")
			(net "M_E_CPU1_SB_DQ<2>")
		)
		(pad "CC72" smd circle
			(at 31.340044 15.750032 180)
			(size 0.450088 0.450088)
			(layers "F.Cu" "F.Mask" "F.Paste")
			(net "GND")
		)
		(pad "CC73" smd circle
			(at 32.280098 15.750032 180)
			(size 0.450088 0.450088)
			(layers "F.Cu" "F.Mask" "F.Paste")
			(net "M_A_CPU1_SB_DQ<1>")
		)
		(pad "CC74" smd circle
			(at 33.219898 15.750032 180)
			(size 0.450088 0.450088)
			(layers "F.Cu" "F.Mask" "F.Paste")
			(net "M_A_CPU1_SB_DQ<2>")
		)
		(pad "CC75" smd circle
			(at 34.159952 15.750032 180)
			(size 0.450088 0.450088)
			(layers "F.Cu" "F.Mask" "F.Paste")
			(net "GND")
		)
		(pad "CD2" smd circle
			(at -33.990026 16.560038 180)
			(size 0.450088 0.450088)
			(layers "F.Cu" "F.Mask" "F.Paste")
			(net "M_G_CPU1_SB_DQS_DP<0>")
		)
		(pad "CD3" smd circle
			(at -33.049972 16.560038 180)
			(size 0.450088 0.450088)
			(layers "F.Cu" "F.Mask" "F.Paste")
			(net "GND")
		)
		(pad "CD4" smd circle
			(at -32.109918 16.560038 180)
			(size 0.450088 0.450088)
			(layers "F.Cu" "F.Mask" "F.Paste")
			(net "M_G_CPU1_SB_DQ<3>")
		)
		(pad "CD5" smd circle
			(at -31.170118 16.560038 180)
			(size 0.450088 0.450088)
			(layers "F.Cu" "F.Mask" "F.Paste")
			(net "PVDD11_S3_P1")
		)
		(pad "CD6" smd circle
			(at -30.230064 16.560038 180)
			(size 0.450088 0.450088)
			(layers "F.Cu" "F.Mask" "F.Paste")
			(net "M_K_CPU1_SB_DQS_DP<0>")
		)
		(pad "CD7" smd circle
			(at -29.29001 16.560038 180)
			(size 0.450088 0.450088)
			(layers "F.Cu" "F.Mask" "F.Paste")
			(net "M_K_CPU1_SB_DQ<3>")
		)
		(pad "CD8" smd circle
			(at -28.349956 16.560038 180)
			(size 0.450088 0.450088)
			(layers "F.Cu" "F.Mask" "F.Paste")
			(net "GND")
		)
		(pad "CD9" smd circle
			(at -27.409902 16.560038 180)
			(size 0.450088 0.450088)
			(layers "F.Cu" "F.Mask" "F.Paste")
			(net "M_L_CPU1_SB_DQS_DP<0>")
		)
		(pad "CD10" smd circle
			(at -26.470102 16.560038 180)
			(size 0.450088 0.450088)
			(layers "F.Cu" "F.Mask" "F.Paste")
			(net "GND")
		)
		(pad "CD11" smd circle
			(at -25.530048 16.560038 180)
			(size 0.450088 0.450088)
			(layers "F.Cu" "F.Mask" "F.Paste")
			(net "M_L_CPU1_SB_DQ<3>")
		)
		(pad "CD12" smd circle
			(at -24.589994 16.560038 180)
			(size 0.450088 0.450088)
			(layers "F.Cu" "F.Mask" "F.Paste")
			(net "PVDD11_S3_P1")
		)
		(pad "CD13" smd circle
			(at -23.64994 16.560038 180)
			(size 0.450088 0.450088)
			(layers "F.Cu" "F.Mask" "F.Paste")
			(net "M_H_CPU1_SB_DQS_DP<0>")
		)
		(pad "CD14" smd circle
			(at -22.709886 16.560038 180)
			(size 0.450088 0.450088)
			(layers "F.Cu" "F.Mask" "F.Paste")
			(net "M_H_CPU1_SB_DQ<3>")
		)
		(pad "CD15" smd circle
			(at -21.770086 16.560038 180)
			(size 0.450088 0.450088)
			(layers "F.Cu" "F.Mask" "F.Paste")
			(net "GND")
		)
		(pad "CD16" smd circle
			(at -20.830032 16.560038 180)
			(size 0.450088 0.450088)
			(layers "F.Cu" "F.Mask" "F.Paste")
			(net "M_J_CPU1_SB_DQS_DP<0>")
		)
		(pad "CD17" smd circle
			(at -19.889978 16.560038 180)
			(size 0.450088 0.450088)
			(layers "F.Cu" "F.Mask" "F.Paste")
			(net "GND")
		)
		(pad "CD18" smd circle
			(at -18.949924 16.560038 180)
			(size 0.450088 0.450088)
			(layers "F.Cu" "F.Mask" "F.Paste")
			(net "M_J_CPU1_SB_DQ<3>")
		)
		(pad "CD19" smd circle
			(at -18.010124 16.560038 180)
			(size 0.450088 0.450088)
			(layers "F.Cu" "F.Mask" "F.Paste")
			(net "PVDD11_S3_P1")
		)
		(pad "CD20" smd circle
			(at -17.07007 16.560038 180)
			(size 0.450088 0.450088)
			(layers "F.Cu" "F.Mask" "F.Paste")
			(net "M_I_CPU1_SB_DQS_DP<0>")
		)
		(pad "CD21" smd circle
			(at -16.130016 16.560038 180)
			(size 0.450088 0.450088)
			(layers "F.Cu" "F.Mask" "F.Paste")
			(net "M_I_CPU1_SB_DQ<3>")
		)
		(pad "CD22" smd circle
			(at -15.189962 16.560038 180)
			(size 0.450088 0.450088)
			(layers "F.Cu" "F.Mask" "F.Paste")
			(net "GND")
		)
		(pad "CD23" smd circle
			(at -14.249908 16.560038 180)
			(size 0.450088 0.450088)
			(layers "F.Cu" "F.Mask" "F.Paste")
			(net "PVDDCR_CPU1_P1")
		)
		(pad "CD24" smd circle
			(at -13.310108 16.560038 180)
			(size 0.450088 0.450088)
			(layers "F.Cu" "F.Mask" "F.Paste")
			(net "PVDDCR_CPU1_P1")
		)
		(pad "CD25" smd circle
			(at -12.370054 16.560038 180)
			(size 0.450088 0.450088)
			(layers "F.Cu" "F.Mask" "F.Paste")
			(net "GND")
		)
		(pad "CD26" smd circle
			(at -11.43 16.560038 180)
			(size 0.450088 0.450088)
			(layers "F.Cu" "F.Mask" "F.Paste")
			(net "PVDDCR_CPU1_P1")
		)
		(pad "CD27" smd circle
			(at -10.489946 16.560038 180)
			(size 0.450088 0.450088)
			(layers "F.Cu" "F.Mask" "F.Paste")
			(net "PVDDCR_CPU1_P1")
		)
		(pad "CD28" smd circle
			(at -9.549892 16.560038 180)
			(size 0.450088 0.450088)
			(layers "F.Cu" "F.Mask" "F.Paste")
			(net "GND")
		)
		(pad "CD29" smd circle
			(at -8.610092 16.560038 180)
			(size 0.450088 0.450088)
			(layers "F.Cu" "F.Mask" "F.Paste")
			(net "PVDDCR_CPU1_P1")
		)
		(pad "CD30" smd circle
			(at -7.670038 16.560038 180)
			(size 0.450088 0.450088)
			(layers "F.Cu" "F.Mask" "F.Paste")
			(net "PVDDCR_CPU1_P1")
		)
		(pad "CD31" smd circle
			(at -6.729984 16.560038 180)
			(size 0.450088 0.450088)
			(layers "F.Cu" "F.Mask" "F.Paste")
			(net "GND")
		)
		(pad "CD32" smd circle
			(at -5.78993 16.560038 180)
			(size 0.450088 0.450088)
			(layers "F.Cu" "F.Mask" "F.Paste")
			(net "PVDDCR_CPU1_P1")
		)
		(pad "CD33" smd circle
			(at -4.849876 16.560038 180)
			(size 0.450088 0.450088)
			(layers "F.Cu" "F.Mask" "F.Paste")
			(net "PVDDCR_CPU1_P1")
		)
		(pad "CD34" smd circle
			(at -3.910076 16.560038 180)
			(size 0.450088 0.450088)
			(layers "F.Cu" "F.Mask" "F.Paste")
			(net "GND")
		)
		(pad "CD35" smd circle
			(at -2.970022 16.560038 180)
			(size 0.450088 0.450088)
			(layers "F.Cu" "F.Mask" "F.Paste")
			(net "P5E_CPU1_P3_TX_DN<0>")
		)
		(pad "CD36" smd circle
			(at -2.029968 16.560038 180)
			(size 0.450088 0.450088)
			(layers "F.Cu" "F.Mask" "F.Paste")
			(net "P5E_CPU1_P3_TX_DP<0>")
		)
		(pad "CD37" smd circle
			(at -1.089914 16.560038 180)
			(size 0.450088 0.450088)
			(layers "F.Cu" "F.Mask" "F.Paste")
			(net "GND")
		)
		(pad "CD39" smd circle
			(at 0.78994 16.560038 180)
			(size 0.450088 0.450088)
			(layers "F.Cu" "F.Mask" "F.Paste")
			(net "GND")
		)
		(pad "CD40" smd circle
			(at 1.729994 16.560038 180)
			(size 0.450088 0.450088)
			(layers "F.Cu" "F.Mask" "F.Paste")
			(net "P5E_CPU1_P1_RX_DP<15>")
		)
		(pad "CD41" smd circle
			(at 2.670048 16.560038 180)
			(size 0.450088 0.450088)
			(layers "F.Cu" "F.Mask" "F.Paste")
			(net "P5E_CPU1_P1_RX_DN<15>")
		)
		(pad "CD42" smd circle
			(at 3.610102 16.560038 180)
			(size 0.450088 0.450088)
			(layers "F.Cu" "F.Mask" "F.Paste")
			(net "GND")
		)
		(pad "CD43" smd circle
			(at 4.549902 16.560038 180)
			(size 0.450088 0.450088)
			(layers "F.Cu" "F.Mask" "F.Paste")
			(net "PVDDCR_CPU1_P1")
		)
		(pad "CD44" smd circle
			(at 5.489956 16.560038 180)
			(size 0.450088 0.450088)
			(layers "F.Cu" "F.Mask" "F.Paste")
			(net "PVDDCR_CPU1_P1")
		)
		(pad "CD45" smd circle
			(at 6.43001 16.560038 180)
			(size 0.450088 0.450088)
			(layers "F.Cu" "F.Mask" "F.Paste")
			(net "GND")
		)
		(pad "CD46" smd circle
			(at 7.370064 16.560038 180)
			(size 0.450088 0.450088)
			(layers "F.Cu" "F.Mask" "F.Paste")
			(net "PVDDCR_CPU1_P1")
		)
		(pad "CD47" smd circle
			(at 8.310118 16.560038 180)
			(size 0.450088 0.450088)
			(layers "F.Cu" "F.Mask" "F.Paste")
			(net "PVDDCR_CPU1_P1")
		)
		(pad "CD48" smd circle
			(at 9.249918 16.560038 180)
			(size 0.450088 0.450088)
			(layers "F.Cu" "F.Mask" "F.Paste")
			(net "GND")
		)
		(pad "CD49" smd circle
			(at 10.189972 16.560038 180)
			(size 0.450088 0.450088)
			(layers "F.Cu" "F.Mask" "F.Paste")
			(net "PVDDCR_CPU1_P1")
		)
		(pad "CD50" smd circle
			(at 11.130026 16.560038 180)
			(size 0.450088 0.450088)
			(layers "F.Cu" "F.Mask" "F.Paste")
			(net "PVDDCR_CPU1_P1")
		)
		(pad "CD51" smd circle
			(at 12.07008 16.560038 180)
			(size 0.450088 0.450088)
			(layers "F.Cu" "F.Mask" "F.Paste")
			(net "GND")
		)
		(pad "CD52" smd circle
			(at 13.00988 16.560038 180)
			(size 0.450088 0.450088)
			(layers "F.Cu" "F.Mask" "F.Paste")
			(net "PVDDCR_CPU1_P1")
		)
		(pad "CD53" smd circle
			(at 13.949934 16.560038 180)
			(size 0.450088 0.450088)
			(layers "F.Cu" "F.Mask" "F.Paste")
			(net "PVDDCR_CPU1_P1")
		)
		(pad "CD54" smd circle
			(at 14.889988 16.560038 180)
			(size 0.450088 0.450088)
			(layers "F.Cu" "F.Mask" "F.Paste")
			(net "GND")
		)
		(pad "CD55" smd circle
			(at 15.830042 16.560038 180)
			(size 0.450088 0.450088)
			(layers "F.Cu" "F.Mask" "F.Paste")
			(net "M_C_CPU1_SB_DQ<3>")
		)
		(pad "CD56" smd circle
			(at 16.770096 16.560038 180)
			(size 0.450088 0.450088)
			(layers "F.Cu" "F.Mask" "F.Paste")
			(net "M_C_CPU1_SB_DQS_DP<0>")
		)
		(pad "CD57" smd circle
			(at 17.709896 16.560038 180)
			(size 0.450088 0.450088)
			(layers "F.Cu" "F.Mask" "F.Paste")
			(net "PVDDIO_P1")
		)
		(pad "CD58" smd circle
			(at 18.64995 16.560038 180)
			(size 0.450088 0.450088)
			(layers "F.Cu" "F.Mask" "F.Paste")
			(net "M_D_CPU1_SB_DQ<3>")
		)
		(pad "CD59" smd circle
			(at 19.590004 16.560038 180)
			(size 0.450088 0.450088)
			(layers "F.Cu" "F.Mask" "F.Paste")
			(net "GND")
		)
		(pad "CD60" smd circle
			(at 20.530058 16.560038 180)
			(size 0.450088 0.450088)
			(layers "F.Cu" "F.Mask" "F.Paste")
			(net "M_D_CPU1_SB_DQS_DP<0>")
		)
		(pad "CD61" smd circle
			(at 21.470112 16.560038 180)
			(size 0.450088 0.450088)
			(layers "F.Cu" "F.Mask" "F.Paste")
			(net "GND")
		)
		(pad "CD62" smd circle
			(at 22.409912 16.560038 180)
			(size 0.450088 0.450088)
			(layers "F.Cu" "F.Mask" "F.Paste")
			(net "M_B_CPU1_SB_DQ<3>")
		)
		(pad "CD63" smd circle
			(at 23.349966 16.560038 180)
			(size 0.450088 0.450088)
			(layers "F.Cu" "F.Mask" "F.Paste")
			(net "M_B_CPU1_SB_DQS_DP<0>")
		)
		(pad "CD64" smd circle
			(at 24.29002 16.560038 180)
			(size 0.450088 0.450088)
			(layers "F.Cu" "F.Mask" "F.Paste")
			(net "PVDDIO_P1")
		)
		(pad "CD65" smd circle
			(at 25.230074 16.560038 180)
			(size 0.450088 0.450088)
			(layers "F.Cu" "F.Mask" "F.Paste")
			(net "M_F_CPU1_SB_DQ<3>")
		)
		(pad "CD66" smd circle
			(at 26.170128 16.560038 180)
			(size 0.450088 0.450088)
			(layers "F.Cu" "F.Mask" "F.Paste")
			(net "GND")
		)
		(pad "CD67" smd circle
			(at 27.109928 16.560038 180)
			(size 0.450088 0.450088)
			(layers "F.Cu" "F.Mask" "F.Paste")
			(net "M_F_CPU1_SB_DQS_DP<0>")
		)
		(pad "CD68" smd circle
			(at 28.049982 16.560038 180)
			(size 0.450088 0.450088)
			(layers "F.Cu" "F.Mask" "F.Paste")
			(net "GND")
		)
		(pad "CD69" smd circle
			(at 28.990036 16.560038 180)
			(size 0.450088 0.450088)
			(layers "F.Cu" "F.Mask" "F.Paste")
			(net "M_E_CPU1_SB_DQ<3>")
		)
		(pad "CD70" smd circle
			(at 29.93009 16.560038 180)
			(size 0.450088 0.450088)
			(layers "F.Cu" "F.Mask" "F.Paste")
			(net "M_E_CPU1_SB_DQS_DP<0>")
		)
		(pad "CD71" smd circle
			(at 30.86989 16.560038 180)
			(size 0.450088 0.450088)
			(layers "F.Cu" "F.Mask" "F.Paste")
			(net "PVDDIO_P1")
		)
		(pad "CD72" smd circle
			(at 31.809944 16.560038 180)
			(size 0.450088 0.450088)
			(layers "F.Cu" "F.Mask" "F.Paste")
			(net "M_A_CPU1_SB_DQ<3>")
		)
		(pad "CD73" smd circle
			(at 32.749998 16.560038 180)
			(size 0.450088 0.450088)
			(layers "F.Cu" "F.Mask" "F.Paste")
			(net "GND")
		)
		(pad "CD74" smd circle
			(at 33.690052 16.560038 180)
			(size 0.450088 0.450088)
			(layers "F.Cu" "F.Mask" "F.Paste")
			(net "M_A_CPU1_SB_DQS_DP<0>")
		)
		(pad "CE1" smd circle
			(at -34.459926 17.370044 180)
			(size 0.450088 0.450088)
			(layers "F.Cu" "F.Mask" "F.Paste")
			(net "GND")
		)
		(pad "CE2" smd circle
			(at -33.519872 17.370044 180)
			(size 0.450088 0.450088)
			(layers "F.Cu" "F.Mask" "F.Paste")
			(net "M_G_CPU1_SB_DQS_DN<0>")
		)
		(pad "CE3" smd circle
			(at -32.580072 17.370044 180)
			(size 0.450088 0.450088)
			(layers "F.Cu" "F.Mask" "F.Paste")
			(net "M_G_CPU1_SB_DQS_DN<5>")
		)
		(pad "CE4" smd circle
			(at -31.640018 17.370044 180)
			(size 0.450088 0.450088)
			(layers "F.Cu" "F.Mask" "F.Paste")
			(net "GND")
		)
		(pad "CE5" smd circle
			(at -30.699964 17.370044 180)
			(size 0.450088 0.450088)
			(layers "F.Cu" "F.Mask" "F.Paste")
			(net "M_K_CPU1_SB_DQS_DN<0>")
		)
		(pad "CE6" smd circle
			(at -29.75991 17.370044 180)
			(size 0.450088 0.450088)
			(layers "F.Cu" "F.Mask" "F.Paste")
			(net "GND")
		)
		(pad "CE7" smd circle
			(at -28.82011 17.370044 180)
			(size 0.450088 0.450088)
			(layers "F.Cu" "F.Mask" "F.Paste")
			(net "M_K_CPU1_SB_DQS_DN<5>")
		)
		(pad "CE8" smd circle
			(at -27.880056 17.370044 180)
			(size 0.450088 0.450088)
			(layers "F.Cu" "F.Mask" "F.Paste")
			(net "GND")
		)
		(pad "CE9" smd circle
			(at -26.940002 17.370044 180)
			(size 0.450088 0.450088)
			(layers "F.Cu" "F.Mask" "F.Paste")
			(net "M_L_CPU1_SB_DQS_DN<0>")
		)
		(pad "CE10" smd circle
			(at -25.999948 17.370044 180)
			(size 0.450088 0.450088)
			(layers "F.Cu" "F.Mask" "F.Paste")
			(net "M_L_CPU1_SB_DQS_DN<5>")
		)
		(pad "CE11" smd circle
			(at -25.059894 17.370044 180)
			(size 0.450088 0.450088)
			(layers "F.Cu" "F.Mask" "F.Paste")
			(net "GND")
		)
		(pad "CE12" smd circle
			(at -24.120094 17.370044 180)
			(size 0.450088 0.450088)
			(layers "F.Cu" "F.Mask" "F.Paste")
			(net "M_H_CPU1_SB_DQS_DN<0>")
		)
		(pad "CE13" smd circle
			(at -23.18004 17.370044 180)
			(size 0.450088 0.450088)
			(layers "F.Cu" "F.Mask" "F.Paste")
			(net "GND")
		)
		(pad "CE14" smd circle
			(at -22.239986 17.370044 180)
			(size 0.450088 0.450088)
			(layers "F.Cu" "F.Mask" "F.Paste")
			(net "M_H_CPU1_SB_DQS_DN<5>")
		)
		(pad "CE15" smd circle
			(at -21.299932 17.370044 180)
			(size 0.450088 0.450088)
			(layers "F.Cu" "F.Mask" "F.Paste")
			(net "GND")
		)
		(pad "CE16" smd circle
			(at -20.359878 17.370044 180)
			(size 0.450088 0.450088)
			(layers "F.Cu" "F.Mask" "F.Paste")
			(net "M_J_CPU1_SB_DQS_DN<0>")
		)
		(pad "CE17" smd circle
			(at -19.420078 17.370044 180)
			(size 0.450088 0.450088)
			(layers "F.Cu" "F.Mask" "F.Paste")
			(net "M_J_CPU1_SB_DQS_DN<5>")
		)
		(pad "CE18" smd circle
			(at -18.480024 17.370044 180)
			(size 0.450088 0.450088)
			(layers "F.Cu" "F.Mask" "F.Paste")
			(net "GND")
		)
		(pad "CE19" smd circle
			(at -17.53997 17.370044 180)
			(size 0.450088 0.450088)
			(layers "F.Cu" "F.Mask" "F.Paste")
			(net "M_I_CPU1_SB_DQS_DN<0>")
		)
	)
)
